(kicad_pcb
	(version 20260206)
	(generator "pcbnew")
	(generator_version "10.0")
	(general
		(thickness 1.6)
		(legacy_teardrops no)
	)
	(paper "A4")
	(title_block
		(title "peb — Lightning_PEB_BRD.brd")
		(comment 1 "Lightning (Wiwynn / Facebook NVMe JBOF) / footprints 2552-2558 of 2563")
	)
	(layers
		(0 "F.Cu" signal "TOP")
		(4 "In1.Cu" signal "L2GND")
		(6 "In2.Cu" signal "L3")
		(8 "In3.Cu" signal "L4VCC")
		(10 "In4.Cu" signal "L5VCC")
		(12 "In5.Cu" signal "L6")
		(14 "In6.Cu" signal "L7GND")
		(2 "B.Cu" signal "BOTTOM")
		(9 "F.Adhes" user "F.Adhesive")
		(11 "B.Adhes" user "B.Adhesive")
		(13 "F.Paste" user "Package Geometry/Pastemask Top")
		(15 "B.Paste" user "Package Geometry/Pastemask Bottom")
		(5 "F.SilkS" user "Ref Des/Silkscreen Top")
		(7 "B.SilkS" user "Ref Des/Silkscreen Bottom")
		(1 "F.Mask" user "Board Geometry/Soldermask Top")
		(3 "B.Mask" user "Board Geometry/Soldermask Bottom")
		(17 "Dwgs.User" user "User.Drawings")
		(19 "Cmts.User" user "User.Comments")
		(21 "Eco1.User" user "User.Eco1")
		(23 "Eco2.User" user "User.Eco2")
		(25 "Edge.Cuts" user "Board Geometry/Outline")
		(27 "Margin" user)
		(31 "F.CrtYd" user "Package Geometry/Place Bound Top")
		(29 "B.CrtYd" user "Package Geometry/Place Bound Bottom")
		(35 "F.Fab" user "Ref Des/Assembly Top")
		(33 "B.Fab" user "Ref Des/Assembly Bottom")
	)
	(footprint ""
		(layer "B.Cu")
		(at 333.4766 -175.7426)
		(property "Reference" "R3215"
			(at 0 0 0)
			(layer "B.SilkS")
			(hide yes)
			(effects
				(font
					(size 1.27 1.27)
				)
				(justify mirror)
			)
		)
		(property "Value" "0R2J-2-GP"
			(at -0.064008 -3.993896 0)
			(unlocked yes)
			(layer "B.Fab")
			(hide yes)
			(effects
				(font
					(size 1.016 1.016)
					(thickness 0.1524)
				)
				(justify mirror)
			)
		)
		(property "Device Type" "R402H16"
			(at -0.064008 -5.517896 0)
			(unlocked yes)
			(layer "B.Fab")
			(hide yes)
			(effects
				(font
					(size 1.016 1.016)
					(thickness 0.1524)
				)
				(justify mirror)
			)
		)
		(duplicate_pad_numbers_are_jumpers no)
		(fp_line
			(start -0.508 -0.9398)
			(end 0.508 -0.9398)
			(stroke
				(width 0.1524)
				(type default)
			)
			(layer "B.SilkS")
		)
		(fp_line
			(start 0.508 -0.9398)
			(end 0.508 0.9398)
			(stroke
				(width 0.1524)
				(type default)
			)
			(layer "B.SilkS")
		)
		(fp_rect
			(start 0.508 0.9398)
			(end -0.508 -0.9398)
			(stroke
				(width 0)
				(type default)
			)
			(fill no)
			(layer "B.CrtYd")
		)
		(fp_rect
			(start 0.508 0.9398)
			(end -0.508 -0.9398)
			(stroke
				(width 0)
				(type default)
			)
			(fill no)
			(layer "B.Fab")
		)
		(pad "1" smd custom
			(at 0 -0.4445 180)
			(size 0.1397 0.1397)
			(layers "B.Cu" "B.Mask" "B.Paste")
			(net "SSD_PERST_Y4")
			(options
				(clearance outline)
				(anchor circle)
			)
			(primitives
				(gr_poly
					(pts
						(arc
							(start -0.1778 0.2794)
							(mid -0.249642 0.249642)
							(end -0.2794 0.1778)
						)
						(arc
							(start -0.2794 -0.1778)
							(mid -0.249642 -0.249642)
							(end -0.1778 -0.2794)
						)
						(arc
							(start 0.1778 -0.2794)
							(mid 0.249642 -0.249642)
							(end 0.2794 -0.1778)
						)
						(arc
							(start 0.2794 0.1778)
							(mid 0.249642 0.249642)
							(end 0.1778 0.2794)
						)
					)
					(width 0)
					(fill yes)
				)
			)
		)
		(pad "2" smd custom
			(at 0 0.4445 180)
			(size 0.1397 0.1397)
			(layers "B.Cu" "B.Mask" "B.Paste")
			(net "SSD_PERST#4_R")
			(options
				(clearance outline)
				(anchor circle)
			)
			(primitives
				(gr_poly
					(pts
						(arc
							(start -0.1778 0.2794)
							(mid -0.249642 0.249642)
							(end -0.2794 0.1778)
						)
						(arc
							(start -0.2794 -0.1778)
							(mid -0.249642 -0.249642)
							(end -0.1778 -0.2794)
						)
						(arc
							(start 0.1778 -0.2794)
							(mid 0.249642 -0.249642)
							(end 0.2794 -0.1778)
						)
						(arc
							(start 0.2794 0.1778)
							(mid 0.249642 0.249642)
							(end 0.1778 0.2794)
						)
					)
					(width 0)
					(fill yes)
				)
			)
		)
	)
	(footprint ""
		(layer "B.Cu")
		(at 239.395 -23.241)
		(property "Reference" "R794"
			(at 0 0 0)
			(layer "B.SilkS")
			(hide yes)
			(effects
				(font
					(size 1.27 1.27)
				)
				(justify mirror)
			)
		)
		(property "Value" "4K7R2F-GP"
			(at -0.064008 -3.993896 0)
			(unlocked yes)
			(layer "B.Fab")
			(hide yes)
			(effects
				(font
					(size 1.016 1.016)
					(thickness 0.1524)
				)
				(justify mirror)
			)
		)
		(property "Device Type" "R402H16"
			(at -0.064008 -5.517896 0)
			(unlocked yes)
			(layer "B.Fab")
			(hide yes)
			(effects
				(font
					(size 1.016 1.016)
					(thickness 0.1524)
				)
				(justify mirror)
			)
		)
		(duplicate_pad_numbers_are_jumpers no)
		(fp_line
			(start -0.508 -0.9398)
			(end 0.508 -0.9398)
			(stroke
				(width 0.1524)
				(type default)
			)
			(layer "B.SilkS")
		)
		(fp_line
			(start 0.508 -0.9398)
			(end 0.508 0.9398)
			(stroke
				(width 0.1524)
				(type default)
			)
			(layer "B.SilkS")
		)
		(fp_rect
			(start 0.508 0.9398)
			(end -0.508 -0.9398)
			(stroke
				(width 0)
				(type default)
			)
			(fill no)
			(layer "B.CrtYd")
		)
		(fp_rect
			(start 0.508 0.9398)
			(end -0.508 -0.9398)
			(stroke
				(width 0)
				(type default)
			)
			(fill no)
			(layer "B.Fab")
		)
		(pad "1" smd custom
			(at 0 -0.4445 180)
			(size 0.1397 0.1397)
			(layers "B.Cu" "B.Mask" "B.Paste")
			(net "GND")
			(options
				(clearance outline)
				(anchor circle)
			)
			(primitives
				(gr_poly
					(pts
						(arc
							(start -0.1778 0.2794)
							(mid -0.249642 0.249642)
							(end -0.2794 0.1778)
						)
						(arc
							(start -0.2794 -0.1778)
							(mid -0.249642 -0.249642)
							(end -0.1778 -0.2794)
						)
						(arc
							(start 0.1778 -0.2794)
							(mid 0.249642 -0.249642)
							(end 0.2794 -0.1778)
						)
						(arc
							(start 0.2794 0.1778)
							(mid 0.249642 0.249642)
							(end 0.1778 0.2794)
						)
					)
					(width 0)
					(fill yes)
				)
			)
		)
		(pad "2" smd custom
			(at 0 0.4445 180)
			(size 0.1397 0.1397)
			(layers "B.Cu" "B.Mask" "B.Paste")
			(net "BOOTSTRAP1")
			(options
				(clearance outline)
				(anchor circle)
			)
			(primitives
				(gr_poly
					(pts
						(arc
							(start -0.1778 0.2794)
							(mid -0.249642 0.249642)
							(end -0.2794 0.1778)
						)
						(arc
							(start -0.2794 -0.1778)
							(mid -0.249642 -0.249642)
							(end -0.1778 -0.2794)
						)
						(arc
							(start 0.1778 -0.2794)
							(mid 0.249642 -0.249642)
							(end 0.2794 -0.1778)
						)
						(arc
							(start 0.2794 0.1778)
							(mid 0.249642 0.249642)
							(end 0.1778 0.2794)
						)
					)
					(width 0)
					(fill yes)
				)
			)
		)
	)
	(footprint ""
		(layer "B.Cu")
		(at 223.393 -23.241 180)
		(property "Reference" "R831"
			(at 0 0 0)
			(layer "B.SilkS")
			(hide yes)
			(effects
				(font
					(size 1.27 1.27)
				)
				(justify mirror)
			)
		)
		(property "Value" "0R2J-2-GP"
			(at -0.064008 -3.993896 180)
			(unlocked yes)
			(layer "B.Fab")
			(hide yes)
			(effects
				(font
					(size 1.016 1.016)
					(thickness 0.1524)
				)
				(justify mirror)
			)
		)
		(property "Device Type" "R402H16"
			(at -0.064008 -5.517896 180)
			(unlocked yes)
			(layer "B.Fab")
			(hide yes)
			(effects
				(font
					(size 1.016 1.016)
					(thickness 0.1524)
				)
				(justify mirror)
			)
		)
		(duplicate_pad_numbers_are_jumpers no)
		(fp_line
			(start 0.508 -0.9398)
			(end 0.508 0.9398)
			(stroke
				(width 0.1524)
				(type default)
			)
			(layer "B.SilkS")
		)
		(fp_line
			(start -0.508 -0.9398)
			(end 0.508 -0.9398)
			(stroke
				(width 0.1524)
				(type default)
			)
			(layer "B.SilkS")
		)
		(fp_rect
			(start 0.508 0.9398)
			(end -0.508 -0.9398)
			(stroke
				(width 0)
				(type default)
			)
			(fill no)
			(layer "B.CrtYd")
		)
		(fp_rect
			(start 0.508 0.9398)
			(end -0.508 -0.9398)
			(stroke
				(width 0)
				(type default)
			)
			(fill no)
			(layer "B.Fab")
		)
		(pad "1" smd custom
			(at 0 -0.4445)
			(size 0.1397 0.1397)
			(layers "B.Cu" "B.Mask" "B.Paste")
			(net "HOST7_RST_N_LS")
			(options
				(clearance outline)
				(anchor circle)
			)
			(primitives
				(gr_poly
					(pts
						(arc
							(start -0.1778 0.2794)
							(mid -0.249642 0.249642)
							(end -0.2794 0.1778)
						)
						(arc
							(start -0.2794 -0.1778)
							(mid -0.249642 -0.249642)
							(end -0.1778 -0.2794)
						)
						(arc
							(start 0.1778 -0.2794)
							(mid 0.249642 -0.249642)
							(end 0.2794 -0.1778)
						)
						(arc
							(start 0.2794 0.1778)
							(mid 0.249642 0.249642)
							(end 0.1778 0.2794)
						)
					)
					(width 0)
					(fill yes)
				)
			)
		)
		(pad "2" smd custom
			(at 0 0.4445)
			(size 0.1397 0.1397)
			(layers "B.Cu" "B.Mask" "B.Paste")
			(net "LBI_ADDR_6_R")
			(options
				(clearance outline)
				(anchor circle)
			)
			(primitives
				(gr_poly
					(pts
						(arc
							(start -0.1778 0.2794)
							(mid -0.249642 0.249642)
							(end -0.2794 0.1778)
						)
						(arc
							(start -0.2794 -0.1778)
							(mid -0.249642 -0.249642)
							(end -0.1778 -0.2794)
						)
						(arc
							(start 0.1778 -0.2794)
							(mid 0.249642 -0.249642)
							(end 0.2794 -0.1778)
						)
						(arc
							(start 0.2794 0.1778)
							(mid 0.249642 0.249642)
							(end 0.1778 0.2794)
						)
					)
					(width 0)
					(fill yes)
				)
			)
		)
	)
	(footprint ""
		(layer "B.Cu")
		(at 70.993 -36.3982 -90)
		(property "Reference" "PR20"
			(at 0 0 90)
			(layer "B.SilkS")
			(hide yes)
			(effects
				(font
					(size 1.27 1.27)
				)
				(justify mirror)
			)
		)
		(property "Value" "0R3J-0-U-GP"
			(at 0.0254 -2.5146 270)
			(unlocked yes)
			(layer "B.Fab")
			(hide yes)
			(effects
				(font
					(size 1.016 1.016)
					(thickness 0.1524)
				)
				(justify mirror)
			)
		)
		(property "Device Type" "R603H22"
			(at 0.0254 -4.0386 270)
			(unlocked yes)
			(layer "B.Fab")
			(hide yes)
			(effects
				(font
					(size 1.016 1.016)
					(thickness 0.1524)
				)
				(justify mirror)
			)
		)
		(duplicate_pad_numbers_are_jumpers no)
		(fp_line
			(start -0.2032 0)
			(end -0.4826 0)
			(stroke
				(width 0.2032)
				(type default)
			)
			(layer "B.SilkS")
		)
		(fp_line
			(start 0.4826 0)
			(end 0.2032 0)
			(stroke
				(width 0.2032)
				(type default)
			)
			(layer "B.SilkS")
		)
		(fp_rect
			(start 0.5842 1.3335)
			(end -0.5842 -1.3335)
			(stroke
				(width 0)
				(type default)
			)
			(fill no)
			(layer "B.CrtYd")
		)
		(fp_rect
			(start 0.5842 1.3335)
			(end -0.5842 -1.3335)
			(stroke
				(width 0)
				(type default)
			)
			(fill no)
			(layer "B.Fab")
		)
		(pad "1" smd custom
			(at 0 -0.762 90)
			(size 0.2159 0.2159)
			(layers "B.Cu" "B.Mask" "B.Paste")
			(net "P3V3_STBY_VBST_RC")
			(options
				(clearance outline)
				(anchor circle)
			)
			(primitives
				(gr_poly
					(pts
						(arc
							(start -0.3302 0.4318)
							(mid -0.402042 0.402042)
							(end -0.4318 0.3302)
						)
						(arc
							(start -0.4318 -0.3302)
							(mid -0.402042 -0.402042)
							(end -0.3302 -0.4318)
						)
						(arc
							(start 0.3302 -0.4318)
							(mid 0.402042 -0.402042)
							(end 0.4318 -0.3302)
						)
						(arc
							(start 0.4318 0.3302)
							(mid 0.402042 0.402042)
							(end 0.3302 0.4318)
						)
					)
					(width 0)
					(fill yes)
				)
			)
		)
		(pad "2" smd custom
			(at 0 0.762 90)
			(size 0.2159 0.2159)
			(layers "B.Cu" "B.Mask" "B.Paste")
			(net "P3V3_STBY_VBST")
			(options
				(clearance outline)
				(anchor circle)
			)
			(primitives
				(gr_poly
					(pts
						(arc
							(start -0.3302 0.4318)
							(mid -0.402042 0.402042)
							(end -0.4318 0.3302)
						)
						(arc
							(start -0.4318 -0.3302)
							(mid -0.402042 -0.402042)
							(end -0.3302 -0.4318)
						)
						(arc
							(start 0.3302 -0.4318)
							(mid 0.402042 -0.402042)
							(end 0.4318 -0.3302)
						)
						(arc
							(start 0.4318 0.3302)
							(mid 0.402042 0.402042)
							(end 0.3302 0.4318)
						)
					)
					(width 0)
					(fill yes)
				)
			)
		)
	)
	(footprint ""
		(layer "B.Cu")
		(at 250.584208 -26.1112 180)
		(property "Reference" "R775"
			(at 0 0 0)
			(layer "B.SilkS")
			(hide yes)
			(effects
				(font
					(size 1.27 1.27)
				)
				(justify mirror)
			)
		)
		(property "Value" "3K3R2F-2-GP"
			(at -0.064008 -3.993896 180)
			(unlocked yes)
			(layer "B.Fab")
			(hide yes)
			(effects
				(font
					(size 1.016 1.016)
					(thickness 0.1524)
				)
				(justify mirror)
			)
		)
		(property "Device Type" "R402H16"
			(at -0.064008 -5.517896 180)
			(unlocked yes)
			(layer "B.Fab")
			(hide yes)
			(effects
				(font
					(size 1.016 1.016)
					(thickness 0.1524)
				)
				(justify mirror)
			)
		)
		(duplicate_pad_numbers_are_jumpers no)
		(fp_line
			(start 0.508 -0.9398)
			(end 0.508 0.9398)
			(stroke
				(width 0.1524)
				(type default)
			)
			(layer "B.SilkS")
		)
		(fp_line
			(start -0.508 -0.9398)
			(end 0.508 -0.9398)
			(stroke
				(width 0.1524)
				(type default)
			)
			(layer "B.SilkS")
		)
		(fp_rect
			(start 0.508 0.9398)
			(end -0.508 -0.9398)
			(stroke
				(width 0)
				(type default)
			)
			(fill no)
			(layer "B.CrtYd")
		)
		(fp_rect
			(start 0.508 0.9398)
			(end -0.508 -0.9398)
			(stroke
				(width 0)
				(type default)
			)
			(fill no)
			(layer "B.Fab")
		)
		(pad "1" smd custom
			(at 0 -0.4445)
			(size 0.1397 0.1397)
			(layers "B.Cu" "B.Mask" "B.Paste")
			(net "P3V3_GPIO")
			(options
				(clearance outline)
				(anchor circle)
			)
			(primitives
				(gr_poly
					(pts
						(arc
							(start -0.1778 0.2794)
							(mid -0.249642 0.249642)
							(end -0.2794 0.1778)
						)
						(arc
							(start -0.2794 -0.1778)
							(mid -0.249642 -0.249642)
							(end -0.1778 -0.2794)
						)
						(arc
							(start 0.1778 -0.2794)
							(mid 0.249642 -0.249642)
							(end 0.2794 -0.1778)
						)
						(arc
							(start 0.2794 0.1778)
							(mid 0.249642 0.249642)
							(end 0.1778 0.2794)
						)
					)
					(width 0)
					(fill yes)
				)
			)
		)
		(pad "2" smd custom
			(at 0 0.4445)
			(size 0.1397 0.1397)
			(layers "B.Cu" "B.Mask" "B.Paste")
			(net "TWI_SDA2")
			(options
				(clearance outline)
				(anchor circle)
			)
			(primitives
				(gr_poly
					(pts
						(arc
							(start -0.1778 0.2794)
							(mid -0.249642 0.249642)
							(end -0.2794 0.1778)
						)
						(arc
							(start -0.2794 -0.1778)
							(mid -0.249642 -0.249642)
							(end -0.1778 -0.2794)
						)
						(arc
							(start 0.1778 -0.2794)
							(mid 0.249642 -0.249642)
							(end 0.2794 -0.1778)
						)
						(arc
							(start 0.2794 0.1778)
							(mid 0.249642 0.249642)
							(end 0.1778 0.2794)
						)
					)
					(width 0)
					(fill yes)
				)
			)
		)
	)
	(footprint ""
		(layer "B.Cu")
		(at 40.64 -201.549 180)
		(property "Reference" "R881"
			(at 0 0 0)
			(layer "B.SilkS")
			(hide yes)
			(effects
				(font
					(size 1.27 1.27)
				)
				(justify mirror)
			)
		)
		(property "Value" "0R2J-2-GP"
			(at -0.064008 -3.993896 180)
			(unlocked yes)
			(layer "B.Fab")
			(hide yes)
			(effects
				(font
					(size 1.016 1.016)
					(thickness 0.1524)
				)
				(justify mirror)
			)
		)
		(property "Device Type" "R402H16"
			(at -0.064008 -5.517896 180)
			(unlocked yes)
			(layer "B.Fab")
			(hide yes)
			(effects
				(font
					(size 1.016 1.016)
					(thickness 0.1524)
				)
				(justify mirror)
			)
		)
		(duplicate_pad_numbers_are_jumpers no)
		(fp_line
			(start 0.508 -0.9398)
			(end 0.508 0.9398)
			(stroke
				(width 0.1524)
				(type default)
			)
			(layer "B.SilkS")
		)
		(fp_line
			(start -0.508 -0.9398)
			(end 0.508 -0.9398)
			(stroke
				(width 0.1524)
				(type default)
			)
			(layer "B.SilkS")
		)
		(fp_rect
			(start 0.508 0.9398)
			(end -0.508 -0.9398)
			(stroke
				(width 0)
				(type default)
			)
			(fill no)
			(layer "B.CrtYd")
		)
		(fp_rect
			(start 0.508 0.9398)
			(end -0.508 -0.9398)
			(stroke
				(width 0)
				(type default)
			)
			(fill no)
			(layer "B.Fab")
		)
		(pad "1" smd custom
			(at 0 -0.4445)
			(size 0.1397 0.1397)
			(layers "B.Cu" "B.Mask" "B.Paste")
			(net "BMC_I2C6_C_FCB_SDA")
			(options
				(clearance outline)
				(anchor circle)
			)
			(primitives
				(gr_poly
					(pts
						(arc
							(start -0.1778 0.2794)
							(mid -0.249642 0.249642)
							(end -0.2794 0.1778)
						)
						(arc
							(start -0.2794 -0.1778)
							(mid -0.249642 -0.249642)
							(end -0.1778 -0.2794)
						)
						(arc
							(start 0.1778 -0.2794)
							(mid 0.249642 -0.249642)
							(end 0.2794 -0.1778)
						)
						(arc
							(start 0.2794 0.1778)
							(mid 0.249642 0.249642)
							(end 0.1778 0.2794)
						)
					)
					(width 0)
					(fill yes)
				)
			)
		)
		(pad "2" smd custom
			(at 0 0.4445)
			(size 0.1397 0.1397)
			(layers "B.Cu" "B.Mask" "B.Paste")
			(net "BUF_I2C6_C_FCB_SDA")
			(options
				(clearance outline)
				(anchor circle)
			)
			(primitives
				(gr_poly
					(pts
						(arc
							(start -0.1778 0.2794)
							(mid -0.249642 0.249642)
							(end -0.2794 0.1778)
						)
						(arc
							(start -0.2794 -0.1778)
							(mid -0.249642 -0.249642)
							(end -0.1778 -0.2794)
						)
						(arc
							(start 0.1778 -0.2794)
							(mid 0.249642 -0.249642)
							(end 0.2794 -0.1778)
						)
						(arc
							(start 0.2794 0.1778)
							(mid 0.249642 0.249642)
							(end 0.1778 0.2794)
						)
					)
					(width 0)
					(fill yes)
				)
			)
		)
	)
	(footprint ""
		(layer "B.Cu")
		(at 17.526 -135.89 90)
		(property "Reference" "R1202"
			(at 0 0 90)
			(layer "B.SilkS")
			(hide yes)
			(effects
				(font
					(size 1.27 1.27)
				)
				(justify mirror)
			)
		)
		(property "Value" "274R2F-GP"
			(at -0.064008 -3.993896 90)
			(unlocked yes)
			(layer "B.Fab")
			(hide yes)
			(effects
				(font
					(size 1.016 1.016)
					(thickness 0.1524)
				)
				(justify mirror)
			)
		)
		(property "Device Type" "R402H16"
			(at -0.064008 -5.517896 90)
			(unlocked yes)
			(layer "B.Fab")
			(hide yes)
			(effects
				(font
					(size 1.016 1.016)
					(thickness 0.1524)
				)
				(justify mirror)
			)
		)
		(duplicate_pad_numbers_are_jumpers no)
		(fp_line
			(start 0.508 -0.9398)
			(end 0.508 0.9398)
			(stroke
				(width 0.1524)
				(type default)
			)
			(layer "B.SilkS")
		)
		(fp_line
			(start -0.508 -0.9398)
			(end 0.508 -0.9398)
			(stroke
				(width 0.1524)
				(type default)
			)
			(layer "B.SilkS")
		)
		(fp_rect
			(start 0.508 0.9398)
			(end -0.508 -0.9398)
			(stroke
				(width 0)
				(type default)
			)
			(fill no)
			(layer "B.CrtYd")
		)
		(fp_rect
			(start 0.508 0.9398)
			(end -0.508 -0.9398)
			(stroke
				(width 0)
				(type default)
			)
			(fill no)
			(layer "B.Fab")
		)
		(pad "1" smd custom
			(at 0 -0.4445 270)
			(size 0.1397 0.1397)
			(layers "B.Cu" "B.Mask" "B.Paste")
			(net "GND")
			(options
				(clearance outline)
				(anchor circle)
			)
			(primitives
				(gr_poly
					(pts
						(arc
							(start -0.1778 0.2794)
							(mid -0.249642 0.249642)
							(end -0.2794 0.1778)
						)
						(arc
							(start -0.2794 -0.1778)
							(mid -0.249642 -0.249642)
							(end -0.1778 -0.2794)
						)
						(arc
							(start 0.1778 -0.2794)
							(mid 0.249642 -0.249642)
							(end 0.2794 -0.1778)
						)
						(arc
							(start 0.2794 0.1778)
							(mid 0.249642 0.249642)
							(end 0.1778 0.2794)
						)
					)
					(width 0)
					(fill yes)
				)
			)
		)
		(pad "2" smd custom
			(at 0 0.4445 270)
			(size 0.1397 0.1397)
			(layers "B.Cu" "B.Mask" "B.Paste")
			(net "BMC_MIOZ")
			(options
				(clearance outline)
				(anchor circle)
			)
			(primitives
				(gr_poly
					(pts
						(arc
							(start -0.1778 0.2794)
							(mid -0.249642 0.249642)
							(end -0.2794 0.1778)
						)
						(arc
							(start -0.2794 -0.1778)
							(mid -0.249642 -0.249642)
							(end -0.1778 -0.2794)
						)
						(arc
							(start 0.1778 -0.2794)
							(mid 0.249642 -0.249642)
							(end 0.2794 -0.1778)
						)
						(arc
							(start 0.2794 0.1778)
							(mid 0.249642 0.249642)
							(end 0.1778 0.2794)
						)
					)
					(width 0)
					(fill yes)
				)
			)
		)
	)
)
